FILE_TYPE = CONNECTIVITY;
{Allegro Design Entry HDL 17.4-2019 S026 (4007227) 1/17/2022}
"PAGE_NUMBER" = 330;
0"NC";
1"GND\g";
2"GND\g";
3"GND\g";
4"P3V3_AUX\g";
5"P3V3_AUX\g";
6"GND\g";
7"P3V3_AUX\g";
8"GND\g";
9"P3V3_AUX\g";
10"GND\g";
11"GND\g";
12"P3V3_AUX\g";
13"GND\g";
14"GND\g";
15"GND\g";
16"GND\g";
17"GND\g";
18"GND\g";
19"GND\g";
20"P3V3_AUX\g";
21"P3V3_AUX\g";
22"P3V3_AUX\g";
23"P3V3_AUX\g";
24"P3V3_AUX\g";
25"GND\g";
26"GND\g";
27"P3V3_AUX\g";
28"P3V3_AUX\g";
29"PRSNT_CABLE_GPU_A3_ISO_N";
30"GND\g";
31"GPU_BASE_ID0";
32"GPU_BASE_ID1";
33"GPU_PEX_STRAP1";
34"GPU_PEX_STRAP0";
35"HGX_DETECT_N_ISO";
36"PRSNT_SWB_ISO_N";
37"PRSNT_CABLE_GPU_A3";
38"PRSNT_CABLE_GPU_A3_N";
39"PRSNT_CABLE_SWB_B2_ISO_N";
40"PRSNT_CABLE_SWB_B1_ISO_N";
41"PRSNT_SWB";
42"PRSNT_CABLE_SWB_B1";
43"PRSNT_CABLE_SWB_B2";
44"PRSNT_CABLE_SWB_B2_N";
45"PRSNT_CABLE_SWB_B1_N";
46"PRSNT_SWB_N";
%"UNIVERSAL_GND"
"1","(-6025,3625)","0","pure_quanta_power","I1";
;
CDS_LIB"pure_quanta_power"
HDL_POWER"GND";
"A"1;
%"UNIVERSAL_GND"
"1","(-6275,7200)","0","pure_quanta_power","I11";
;
CDS_LIB"pure_quanta_power"
HDL_POWER"GND";
"A"2;
%"Q_RES"
"2","(-6275,7525)","2","pure_quanta","I12";
;
LOCATION"R8001"
SEC"1"
WATTAGE"1/16W"
MATERIAL"EMPTY"
VALUE"100K"
TOLERANCE"1%"
PACK_TYPE"0402LF"
SEC_TYPE"0402LF"
CDS_LIB"pure_quanta"
PART_NUMBER"CS41002FB09";
"A"
$PN"1"46;
"B"
$PN"2"2;
%"Q_RES"
"2","(-6300,8150)","2","pure_quanta","I13";
;
LOCATION"R4058"
SEC"1"
TOLERANCE"1%"
PACK_TYPE"0402LF"
WATTAGE"1/16W"
MATERIAL"CHIP"
VALUE"10K"
SEC_TYPE"0402LF"
CDS_LIB"pure_quanta"
PART_NUMBER"CS31002FB08";
"A"
$PN"1"20;
"B"
$PN"2"46;
%"UNIVERSAL_GND"
"1","(-6075,5425)","0","pure_quanta_power","I14";
;
CDS_LIB"pure_quanta_power"
HDL_POWER"GND";
"A"3;
%"Q_RES"
"2","(-6050,4575)","2","pure_quanta","I15";
;
LOCATION"R9006"
$SEC"1"
CDS_SEC"1"
MATERIAL"CHIP"
VALUE"10K"
WATTAGE"1/16W"
PACK_TYPE"0402LF"
TOLERANCE"1%"
CDS_LIB"pure_quanta"
PART_NUMBER"CS31002FB08";
"A"
$PN"1"4;
"B"
$PN"2"44;
%"UNIVERSAL_POWER"
"1","(-6050,4875)","0","pure_quanta_power","I16";
;
HDL_POWER"P3V3_AUX"
CDS_LIB"pure_quanta_power";
"A"4;
%"Q_RES"
"2","(-5650,4900)","2","pure_quanta","I17";
;
LOCATION"R9008"
$SEC"1"
CDS_SEC"1"
PACK_TYPE"0402LF"
VALUE"4.7K"
MATERIAL"CHIP"
WATTAGE"1/16W"
TOLERANCE"5%"
CDS_LIB"pure_quanta"
PART_NUMBER"CS24702JB10";
"A"
$PN"1"5;
"B"
$PN"2"43;
%"UNIVERSAL_POWER"
"1","(-5650,5250)","0","pure_quanta_power","I18";
;
HDL_POWER"P3V3_AUX"
CDS_LIB"pure_quanta_power";
"A"5;
%"UNIVERSAL_GND"
"1","(-5700,5500)","0","pure_quanta_power","I19";
;
CDS_LIB"pure_quanta_power"
HDL_POWER"GND";
"A"6;
%"Q_RES"
"2","(-6025,3950)","2","pure_quanta","I2";
;
LOCATION"R9007"
$SEC"1"
CDS_SEC"1"
MATERIAL"EMPTY"
PACK_TYPE"0402LF"
VALUE"100K"
WATTAGE"1/16W"
TOLERANCE"1%"
CDS_LIB"pure_quanta"
PART_NUMBER"CS41002FB09";
"A"
$PN"1"44;
"B"
$PN"2"1;
%"Q_RES"
"2","(-6075,5750)","2","pure_quanta","I20";
;
LOCATION"R9003"
SEC"1"
VALUE"100K"
TOLERANCE"1%"
WATTAGE"1/16W"
MATERIAL"EMPTY"
PACK_TYPE"0402LF"
SEC_TYPE"0402LF"
CDS_LIB"pure_quanta"
PART_NUMBER"CS41002FB09";
"A"
$PN"1"45;
"B"
$PN"2"3;
%"MOSFET_NCH_DUAL"
"1","(-5750,6050)","0","pure_quanta","I21";
;
LOCATION"Q9000"
SEC"1"
PART_TYPE"SMLF"
VALUE"PJT138K"
MATERIAL"IC"
NEEDS_NO_SIZE"TRUE"
SEC_TYPE""
CDS_LIB"pure_quanta"
CDS_LMAN_SYM_OUTLINE"-150,150,150,-150"
PART_NUMBER"BAM138K0003";
"D1"
$PN"6"42;
"G1"
$PN"2"45;
"S1"
$PN"1"6;
%"MOSFET_NCH_DUAL"
"2","(-4700,4600)","0","pure_quanta","I22";
;
LOCATION"Q9001"
$SEC"2"
CDS_SEC"2"
PART_TYPE"SMLF"
VALUE"PJT138K"
MATERIAL"IC"
NEEDS_NO_SIZE"TRUE"
CDS_LMAN_SYM_OUTLINE"-150,150,150,-150"
CDS_LIB"pure_quanta"
PART_NUMBER"BAM138K0003";
"S2"
$PN"4"18;
"G2"
$PN"5"43;
"D2"
$PN"3"39;
%"Q_RES"
"2","(-4650,5150)","2","pure_quanta","I23";
;
LOCATION"R9009"
$SEC"1"
CDS_SEC"1"
TOLERANCE"5%"
VALUE"4.7K"
MATERIAL"CHIP"
WATTAGE"1/16W"
PACK_TYPE"0402LF"
CDS_LIB"pure_quanta"
PART_NUMBER"CS24702JB10";
"A"
$PN"1"7;
"B"
$PN"2"39;
%"UNIVERSAL_POWER"
"1","(-4650,5425)","0","pure_quanta_power","I24";
;
HDL_POWER"P3V3_AUX"
CDS_LIB"pure_quanta_power";
"A"7;
%"UNIVERSAL_GND"
"1","(-4700,5875)","0","pure_quanta_power","I25";
;
CDS_LIB"pure_quanta_power"
HDL_POWER"GND";
"A"8;
%"Q_RES"
"2","(-5700,6700)","2","pure_quanta","I26";
;
LOCATION"R9004"
$SEC"1"
CDS_SEC"1"
PACK_TYPE"0402LF"
MATERIAL"CHIP"
WATTAGE"1/16W"
TOLERANCE"5%"
VALUE"4.7K"
CDS_LIB"pure_quanta"
PART_NUMBER"CS24702JB10";
"A"
$PN"1"9;
"B"
$PN"2"42;
%"UNIVERSAL_POWER"
"1","(-5700,7050)","0","pure_quanta_power","I27";
;
HDL_POWER"P3V3_AUX"
CDS_LIB"pure_quanta_power";
"A"9;
%"UNIVERSAL_GND"
"1","(-5675,7275)","0","pure_quanta_power","I28";
;
CDS_LIB"pure_quanta_power"
HDL_POWER"GND";
"A"10;
%"MOSFET_NCH_DUAL"
"1","(-5725,7825)","0","pure_quanta","I29";
;
LOCATION"Q8000"
SEC"1"
MATERIAL"IC"
VALUE"PJT138K"
PART_TYPE"SMLF"
CDS_LMAN_SYM_OUTLINE"-150,150,150,-150"
NEEDS_NO_SIZE"TRUE"
CDS_LIB"pure_quanta"
SEC_TYPE""
PART_NUMBER"BAM138K0003";
"D1"
$PN"6"41;
"G1"
$PN"2"46;
"S1"
$PN"1"10;
%"MOSFET_NCH_DUAL"
"1","(-5700,4250)","0","pure_quanta","I3";
;
LOCATION"Q9001"
$SEC"1"
CDS_SEC"1"
PART_TYPE"SMLF"
MATERIAL"IC"
VALUE"PJT138K"
NEEDS_NO_SIZE"TRUE"
CDS_LMAN_SYM_OUTLINE"-150,150,150,-150"
CDS_LIB"pure_quanta"
PART_NUMBER"BAM138K0003";
"D1"
$PN"6"43;
"G1"
$PN"2"44;
"S1"
$PN"1"14;
%"MOSFET_NCH_DUAL"
"2","(-4900,8175)","0","pure_quanta","I30";
;
LOCATION"Q8000"
SEC"2"
MATERIAL"IC"
PART_TYPE"SMLF"
VALUE"PJT138K"
CDS_LMAN_SYM_OUTLINE"-150,150,150,-150"
NEEDS_NO_SIZE"TRUE"
CDS_LIB"pure_quanta"
SEC_TYPE""
PART_NUMBER"BAM138K0003";
"S2"
$PN"4"11;
"G2"
$PN"5"41;
"D2"
$PN"3"36;
%"MOSFET_NCH_DUAL"
"2","(-4750,6400)","0","pure_quanta","I31";
;
LOCATION"Q9000"
SEC"2"
PART_TYPE"SMLF"
VALUE"PJT138K"
MATERIAL"IC"
NEEDS_NO_SIZE"TRUE"
SEC_TYPE""
CDS_LMAN_SYM_OUTLINE"-150,150,150,-150"
CDS_LIB"pure_quanta"
PART_NUMBER"BAM138K0003";
"S2"
$PN"4"8;
"G2"
$PN"5"42;
"D2"
$PN"3"40;
%"Q_RES"
"2","(-4700,6950)","2","pure_quanta","I32";
;
LOCATION"R9005"
$SEC"1"
CDS_SEC"1"
VALUE"4.7K"
PACK_TYPE"0402LF"
MATERIAL"CHIP"
WATTAGE"1/16W"
TOLERANCE"5%"
CDS_LIB"pure_quanta"
PART_NUMBER"CS24702JB10";
"A"
$PN"1"12;
"B"
$PN"2"40;
%"UNIVERSAL_GND"
"1","(-4850,7650)","0","pure_quanta_power","I33";
;
CDS_LIB"pure_quanta_power"
HDL_POWER"GND";
"A"11;
%"UNIVERSAL_POWER"
"1","(-4700,7225)","0","pure_quanta_power","I34";
;
HDL_POWER"P3V3_AUX"
CDS_LIB"pure_quanta_power";
"A"12;
%"UNIVERSAL_GND"
"1","(-4150,7750)","0","pure_quanta_power","I35";
;
CDS_LIB"pure_quanta_power"
HDL_POWER"GND";
"A"13;
%"Q_CAP"
"1","(-4150,8125)","0","pure_quanta","I36";
;
LOCATION"C8000"
$SEC"1"
CDS_SEC"1"
PACK_TYPE"0402"
VALUE"1000PF"
MATERIAL"EMPTY"
TOLERANCE"5%"
VOLTAGE"50V"
CDS_LIB"pure_quanta"
PART_NUMBER"TMP_QCH21006JB10";
"B"
$PN"2"13;
"A"
$PN"1"36;
%"UNIVERSAL_GND"
"1","(-5650,3700)","0","pure_quanta_power","I4";
;
CDS_LIB"pure_quanta_power"
HDL_POWER"GND";
"A"14;
%"UNIVERSAL_GND"
"1","(-3950,4175)","0","pure_quanta_power","I41";
;
CDS_LIB"pure_quanta_power"
HDL_POWER"GND";
"A"15;
%"Q_CAP"
"1","(-3950,4550)","0","pure_quanta","I42";
;
LOCATION"C9001"
$SEC"1"
CDS_SEC"1"
VALUE"1000PF"
VOLTAGE"50V"
MATERIAL"EMPTY"
PACK_TYPE"0402"
TOLERANCE"5%"
CDS_LIB"pure_quanta"
PART_NUMBER"TMP_QCH21006JB10";
"B"
$PN"2"15;
"A"
$PN"1"39;
%"UNIVERSAL_GND"
"1","(-4000,5975)","0","pure_quanta_power","I44";
;
CDS_LIB"pure_quanta_power"
HDL_POWER"GND";
"A"16;
%"Q_CAP"
"1","(-4000,6350)","0","pure_quanta","I45";
;
LOCATION"C9000"
$SEC"1"
CDS_SEC"1"
VALUE"1000PF"
VOLTAGE"50V"
PACK_TYPE"0402"
MATERIAL"EMPTY"
TOLERANCE"5%"
CDS_LIB"pure_quanta"
PART_NUMBER"TMP_QCH21006JB10";
"B"
$PN"2"16;
"A"
$PN"1"40;
%"UNIVERSAL_GND"
"1","(-1300,7200)","0","pure_quanta_power","I49";
;
CDS_LIB"pure_quanta_power"
HDL_POWER"GND";
"A"17;
%"UNIVERSAL_GND"
"1","(-4650,4075)","0","pure_quanta_power","I5";
;
CDS_LIB"pure_quanta_power"
HDL_POWER"GND";
"A"18;
%"Q_RES"
"2","(-1300,7525)","2","pure_quanta","I50";
;
LOCATION"R9015"
$SEC"1"
CDS_SEC"1"
PACK_TYPE"0402LF"
WATTAGE"1/16W"
MATERIAL"EMPTY"
TOLERANCE"1%"
VALUE"100K"
CDS_LIB"pure_quanta"
PART_NUMBER"CS41002FB09";
"A"
$PN"1"38;
"B"
$PN"2"17;
%"Q_RES"
"2","(-1325,8150)","2","pure_quanta","I51";
;
LOCATION"R9014"
$SEC"1"
CDS_SEC"1"
VALUE"10K"
PACK_TYPE"0402LF"
MATERIAL"CHIP"
WATTAGE"1/16W"
TOLERANCE"1%"
CDS_LIB"pure_quanta"
PART_NUMBER"CS31002FB08";
"A"
$PN"1"23;
"B"
$PN"2"38;
%"MOSFET_NCH_DUAL"
"1","(-975,7825)","0","pure_quanta","I52";
;
LOCATION"Q9002"
$SEC"1"
CDS_SEC"1"
VALUE"PJT138K"
PART_TYPE"SMLF"
MATERIAL"IC"
NEEDS_NO_SIZE"TRUE"
CDS_LMAN_SYM_OUTLINE"-150,150,150,-150"
CDS_LIB"pure_quanta"
PART_NUMBER"BAM138K0003";
"D1"
$PN"6"37;
"G1"
$PN"2"38;
"S1"
$PN"1"19;
%"UNIVERSAL_GND"
"1","(-925,7275)","0","pure_quanta_power","I53";
;
CDS_LIB"pure_quanta_power"
HDL_POWER"GND";
"A"19;
%"UNIVERSAL_POWER"
"1","(-6300,8450)","0","pure_quanta_power","I54";
;
HDL_POWER"P3V3_AUX"
CDS_LIB"pure_quanta_power";
"A"20;
%"Q_RES"
"2","(-5675,8475)","2","pure_quanta","I55";
;
LOCATION"R8002"
$SEC"1"
CDS_SEC"1"
PACK_TYPE"0402LF"
WATTAGE"1/16W"
VALUE"4.7K"
MATERIAL"CHIP"
TOLERANCE"5%"
CDS_LIB"pure_quanta"
PART_NUMBER"CS24702JB10";
"A"
$PN"1"21;
"B"
$PN"2"41;
%"UNIVERSAL_POWER"
"1","(-5675,8825)","0","pure_quanta_power","I56";
;
HDL_POWER"P3V3_AUX"
CDS_LIB"pure_quanta_power";
"A"21;
%"Q_RES"
"2","(-4850,8725)","2","pure_quanta","I57";
;
LOCATION"R8003"
$SEC"1"
CDS_SEC"1"
PACK_TYPE"0402LF"
WATTAGE"1/16W"
TOLERANCE"5%"
VALUE"4.7K"
MATERIAL"CHIP"
CDS_LIB"pure_quanta"
PART_NUMBER"CS24702JB10";
"A"
$PN"1"22;
"B"
$PN"2"36;
%"UNIVERSAL_POWER"
"1","(-4850,9000)","0","pure_quanta_power","I58";
;
HDL_POWER"P3V3_AUX"
CDS_LIB"pure_quanta_power";
"A"22;
%"UNIVERSAL_POWER"
"1","(-1325,8450)","0","pure_quanta_power","I60";
;
HDL_POWER"P3V3_AUX"
CDS_LIB"pure_quanta_power";
"A"23;
%"Q_RES"
"2","(-925,8475)","2","pure_quanta","I61";
;
LOCATION"R9016"
$SEC"1"
CDS_SEC"1"
PACK_TYPE"0402LF"
TOLERANCE"5%"
VALUE"4.7K"
MATERIAL"CHIP"
WATTAGE"1/16W"
CDS_LIB"pure_quanta"
PART_NUMBER"CS24702JB10";
"A"
$PN"1"24;
"B"
$PN"2"37;
%"UNIVERSAL_POWER"
"1","(-925,8825)","0","pure_quanta_power","I62";
;
HDL_POWER"P3V3_AUX"
CDS_LIB"pure_quanta_power";
"A"24;
%"UNIVERSAL_GND"
"1","(75,7650)","0","pure_quanta_power","I63";
;
CDS_LIB"pure_quanta_power"
HDL_POWER"GND";
"A"25;
%"Q_RES"
"1","(650,3750)","0","pure_quanta","I64";
;
LOCATION"R3441"
$SEC"1"
CDS_SEC"1"
TOLERANCE"5%"
WATTAGE"1/16W"
MATERIAL"CHIP"
VALUE"0"
PACK_TYPE"0402LF"
CDS_LIB"pure_quanta"
PART_NUMBER"CS00002JB13";
"B"
$PN"2"30;
"A"
$PN"1"32;
%"Q_RES"
"1","(650,3950)","0","pure_quanta","I65";
;
LOCATION"R3440"
$SEC"1"
CDS_SEC"1"
PACK_TYPE"0402LF"
MATERIAL"EMPTY"
VALUE"0"
TOLERANCE"5%"
WATTAGE"1/16W"
CDS_LIB"pure_quanta"
PART_NUMBER"CS00002JB13";
"B"
$PN"2"30;
"A"
$PN"1"31;
%"Q_RES"
"1","(650,3350)","0","pure_quanta","I66";
;
LOCATION"R3443"
$SEC"1"
CDS_SEC"1"
TOLERANCE"5%"
VALUE"0"
WATTAGE"1/16W"
MATERIAL"CHIP"
PACK_TYPE"0402LF"
CDS_LIB"pure_quanta"
PART_NUMBER"CS00002JB13";
"B"
$PN"2"30;
"A"
$PN"1"33;
%"Q_RES"
"1","(650,3550)","0","pure_quanta","I67";
;
LOCATION"R3442"
$SEC"1"
CDS_SEC"1"
TOLERANCE"5%"
WATTAGE"1/16W"
MATERIAL"CHIP"
VALUE"0"
PACK_TYPE"0402LF"
CDS_LIB"pure_quanta"
PART_NUMBER"CS00002JB13";
"B"
$PN"2"30;
"A"
$PN"1"34;
%"UNIVERSAL_GND"
"1","(1700,2925)","0","pure_quanta_power","I68";
;
CDS_LIB"pure_quanta_power"
HDL_POWER"GND";
"A"30;
%"Q_RES"
"1","(675,4175)","0","pure_quanta","I69";
;
LOCATION"R2656"
$SEC"1"
CDS_SEC"1"
VALUE"100"
PACK_TYPE"0402LF"
WATTAGE"1/16W"
MATERIAL"EMPTY"
TOLERANCE"1%"
CDS_LIB"pure_quanta"
PART_NUMBER"CS11002FB07";
"B"
$PN"2"30;
"A"
$PN"1"35;
%"UNIVERSAL_GND"
"1","(775,7750)","0","pure_quanta_power","I70";
;
CDS_LIB"pure_quanta_power"
HDL_POWER"GND";
"A"26;
%"Q_CAP"
"1","(775,8125)","0","pure_quanta","I71";
;
LOCATION"C9002"
$SEC"1"
CDS_SEC"1"
VALUE"1000PF"
TOLERANCE"5%"
MATERIAL"EMPTY"
PACK_TYPE"0402"
VOLTAGE"50V"
CDS_LIB"pure_quanta"
PART_NUMBER"TMP_QCH21006JB10";
"B"
$PN"2"26;
"A"
$PN"1"29;
%"Q_RES"
"2","(75,8725)","2","pure_quanta","I72";
;
LOCATION"R9017"
$SEC"1"
CDS_SEC"1"
PACK_TYPE"0402LF"
WATTAGE"1/16W"
TOLERANCE"5%"
VALUE"4.7K"
MATERIAL"CHIP"
CDS_LIB"pure_quanta"
PART_NUMBER"CS24702JB10";
"A"
$PN"1"27;
"B"
$PN"2"29;
%"UNIVERSAL_POWER"
"1","(75,9000)","0","pure_quanta_power","I73";
;
HDL_POWER"P3V3_AUX"
CDS_LIB"pure_quanta_power";
"A"27;
%"MOSFET_NCH_DUAL"
"2","(25,8175)","0","pure_quanta","I75";
;
LOCATION"Q9002"
$SEC"2"
CDS_SEC"2"
PART_TYPE"SMLF"
VALUE"PJT138K"
MATERIAL"IC"
NEEDS_NO_SIZE"TRUE"
CDS_LMAN_SYM_OUTLINE"-150,150,150,-150"
CDS_LIB"pure_quanta"
PART_NUMBER"BAM138K0003";
"S2"
$PN"4"25;
"G2"
$PN"5"37;
"D2"
$PN"3"29;
%"Q_RES"
"2","(-6100,6375)","2","pure_quanta","I8";
;
LOCATION"R9002"
SEC"1"
PACK_TYPE"0402LF"
VALUE"10K"
WATTAGE"1/16W"
MATERIAL"CHIP"
TOLERANCE"1%"
SEC_TYPE"0402LF"
CDS_LIB"pure_quanta"
PART_NUMBER"CS31002FB08";
"A"
$PN"1"28;
"B"
$PN"2"45;
%"UNIVERSAL_POWER"
"1","(-6100,6675)","0","pure_quanta_power","I9";
;
HDL_POWER"P3V3_AUX"
CDS_LIB"pure_quanta_power";
"A"28;
END.
